(kicad_pcb
	(version 20260206)
	(generator "pcbnew")
	(generator_version "10.0")
	(general
		(thickness 1.6)
		(legacy_teardrops no)
	)
	(paper "A4")
	(title_block
		(title "01162023_DA0F0TEBIF0_F0T_Expander_BD_F_brd_V02_OCP.brd")
		(comment 1 "Grand Teton / footprints 7031-7036 of 9728")
	)
	(layers
		(0 "F.Cu" signal "TOP")
		(4 "In1.Cu" signal "GND")
		(6 "In2.Cu" signal "VCC")
		(8 "In3.Cu" signal "VCC1")
		(10 "In4.Cu" signal "GND1")
		(12 "In5.Cu" signal "IN1")
		(14 "In6.Cu" signal "GND2")
		(16 "In7.Cu" signal "IN2")
		(18 "In8.Cu" signal "GND3")
		(20 "In9.Cu" signal "IN3")
		(22 "In10.Cu" signal "GND4")
		(24 "In11.Cu" signal "IN4")
		(26 "In12.Cu" signal "GND5")
		(28 "In13.Cu" signal "IN5")
		(30 "In14.Cu" signal "GND6")
		(32 "In15.Cu" signal "IN6")
		(34 "In16.Cu" signal "GND7")
		(2 "B.Cu" signal "BOTTOM")
		(9 "F.Adhes" user "F.Adhesive")
		(11 "B.Adhes" user "B.Adhesive")
		(13 "F.Paste" user "Package Geometry/Pastemask Top")
		(15 "B.Paste" user "Package Geometry/Pastemask Bottom")
		(5 "F.SilkS" user "Ref Des/Silkscreen Top")
		(7 "B.SilkS" user "Ref Des/Silkscreen Bottom")
		(1 "F.Mask" user "Board Geometry/Soldermask Top")
		(3 "B.Mask" user "Board Geometry/Soldermask Bottom")
		(17 "Dwgs.User" user "User.Drawings")
		(19 "Cmts.User" user "User.Comments")
		(21 "Eco1.User" user "User.Eco1")
		(23 "Eco2.User" user "User.Eco2")
		(25 "Edge.Cuts" user "Board Geometry/Outline")
		(27 "Margin" user)
		(31 "F.CrtYd" user "Package Geometry/Place Bound Top")
		(29 "B.CrtYd" user "Package Geometry/Place Bound Bottom")
		(35 "F.Fab" user "Ref Des/Assembly Top")
		(33 "B.Fab" user "Ref Des/Assembly Bottom")
	)
	(footprint ""
		(layer "F.Cu")
		(at 193.745104 -413.45485 -90)
		(property "Reference" "U443"
			(at -2.551938 -3.27787 0)
			(unlocked yes)
			(layer "F.SilkS")
			(effects
				(font
					(size 0.7874 0.5842)
					(thickness 0.1524)
				)
			)
		)
		(property "Value" ""
			(at 0 0 270)
			(layer "F.Fab")
			(effects
				(font
					(size 1.27 1.27)
				)
			)
		)
		(duplicate_pad_numbers_are_jumpers no)
		(fp_line
			(start -2.032 1.549908)
			(end -2.032 -1.549908)
			(stroke
				(width 0.1524)
				(type default)
			)
			(layer "F.SilkS")
		)
		(fp_line
			(start 2.032 1.549908)
			(end -2.032 1.549908)
			(stroke
				(width 0.1524)
				(type default)
			)
			(layer "F.SilkS")
		)
		(fp_line
			(start 0 -0.762)
			(end 0.508 -1.549908)
			(stroke
				(width 0.1524)
				(type default)
			)
			(layer "F.SilkS")
		)
		(fp_line
			(start -2.032 -1.549908)
			(end -0.508 -1.549908)
			(stroke
				(width 0.1524)
				(type default)
			)
			(layer "F.SilkS")
		)
		(fp_line
			(start -0.508 -1.549908)
			(end 0 -0.762)
			(stroke
				(width 0.1524)
				(type default)
			)
			(layer "F.SilkS")
		)
		(fp_line
			(start 0.508 -1.549908)
			(end 2.032 -1.549908)
			(stroke
				(width 0.1524)
				(type default)
			)
			(layer "F.SilkS")
		)
		(fp_line
			(start 2.032 -1.549908)
			(end 2.032 1.549908)
			(stroke
				(width 0.1524)
				(type default)
			)
			(layer "F.SilkS")
		)
		(fp_poly
			(pts
				(xy -3.2004 -1.45796) (xy -3.2004 -0.44196) (xy -2.1844 -0.94996)
			)
			(stroke
				(width 0)
				(type default)
			)
			(fill yes)
			(layer "F.SilkS")
		)
		(fp_line
			(start -0.849884 1.549908)
			(end -0.849884 -1.549908)
			(stroke
				(width 0.1)
				(type default)
			)
			(layer "F.Fab")
		)
		(fp_line
			(start 0.849884 1.549908)
			(end -0.849884 1.549908)
			(stroke
				(width 0.1)
				(type default)
			)
			(layer "F.Fab")
		)
		(fp_line
			(start -0.849884 -1.549908)
			(end 0.849884 -1.549908)
			(stroke
				(width 0.1)
				(type default)
			)
			(layer "F.Fab")
		)
		(fp_line
			(start 0.849884 -1.549908)
			(end 0.849884 1.549908)
			(stroke
				(width 0.1)
				(type default)
			)
			(layer "F.Fab")
		)
		(fp_poly
			(pts
				(xy -3.2004 -1.45796) (xy -3.2004 -0.44196) (xy -2.1844 -0.94996)
			)
			(stroke
				(width 0)
				(type default)
			)
			(fill yes)
			(layer "F.Fab")
		)
		(pad "1" smd rect
			(at -1.35001 -0.94996 180)
			(size 0.6096 1.0668)
			(layers "F.Cu" "F.Mask" "F.Paste")
			(net "UV_P2V5_COMP")
		)
		(pad "2" smd rect
			(at -1.35001 0 180)
			(size 0.6096 1.0668)
			(layers "F.Cu" "F.Mask" "F.Paste")
			(net "GND")
		)
		(pad "3" smd rect
			(at -1.35001 0.94996 180)
			(size 0.6096 1.0668)
			(layers "F.Cu" "F.Mask" "F.Paste")
			(net "P12V_AUX_FP_TRIGGER")
		)
		(pad "4" smd rect
			(at 1.35001 0.94996 180)
			(size 0.6096 1.0668)
			(layers "F.Cu" "F.Mask" "F.Paste")
			(net "HSC_UV_R2_N")
		)
		(pad "5" smd rect
			(at 1.35001 -0.94996 180)
			(size 0.6096 1.0668)
			(layers "F.Cu" "F.Mask" "F.Paste")
			(net "P12V_AUX")
		)
	)
	(footprint ""
		(layer "F.Cu")
		(at 452.543672 -47.92091)
		(property "Reference" "R669"
			(at 0 0 0)
			(layer "F.SilkS")
			(hide yes)
			(effects
				(font
					(size 1.27 1.27)
				)
			)
		)
		(property "Value" ""
			(at 0 0 0)
			(layer "F.Fab")
			(effects
				(font
					(size 1.27 1.27)
				)
			)
		)
		(duplicate_pad_numbers_are_jumpers no)
		(fp_line
			(start -0.7874 -0.4064)
			(end 0.7874 -0.4064)
			(stroke
				(width 0.1524)
				(type default)
			)
			(layer "F.SilkS")
		)
		(fp_line
			(start -0.7874 0.4064)
			(end -0.7874 -0.4064)
			(stroke
				(width 0.1524)
				(type default)
			)
			(layer "F.SilkS")
		)
		(fp_line
			(start 0.7874 -0.4064)
			(end 0.7874 0.4064)
			(stroke
				(width 0.1524)
				(type default)
			)
			(layer "F.SilkS")
		)
		(fp_line
			(start 0.7874 0.4064)
			(end -0.7874 0.4064)
			(stroke
				(width 0.1524)
				(type default)
			)
			(layer "F.SilkS")
		)
		(fp_line
			(start -0.67945 -0.305054)
			(end -0.12065 -0.305054)
			(stroke
				(width 0.1)
				(type default)
			)
			(layer "F.Fab")
		)
		(fp_line
			(start -0.67945 0.3048)
			(end -0.67945 -0.305054)
			(stroke
				(width 0.1)
				(type default)
			)
			(layer "F.Fab")
		)
		(fp_line
			(start -0.12065 -0.305054)
			(end -0.12065 -0.2794)
			(stroke
				(width 0.1)
				(type default)
			)
			(layer "F.Fab")
		)
		(fp_line
			(start -0.12065 -0.2794)
			(end 0.12065 -0.2794)
			(stroke
				(width 0.1)
				(type default)
			)
			(layer "F.Fab")
		)
		(fp_line
			(start -0.12065 0.2794)
			(end -0.12065 0.3048)
			(stroke
				(width 0.1)
				(type default)
			)
			(layer "F.Fab")
		)
		(fp_line
			(start -0.12065 0.3048)
			(end -0.67945 0.3048)
			(stroke
				(width 0.1)
				(type default)
			)
			(layer "F.Fab")
		)
		(fp_line
			(start 0.120396 0.2794)
			(end -0.12065 0.2794)
			(stroke
				(width 0.1)
				(type default)
			)
			(layer "F.Fab")
		)
		(fp_line
			(start 0.120396 0.3048)
			(end 0.120396 0.2794)
			(stroke
				(width 0.1)
				(type default)
			)
			(layer "F.Fab")
		)
		(fp_line
			(start 0.12065 -0.3048)
			(end 0.67945 -0.3048)
			(stroke
				(width 0.1)
				(type default)
			)
			(layer "F.Fab")
		)
		(fp_line
			(start 0.12065 -0.2794)
			(end 0.12065 -0.3048)
			(stroke
				(width 0.1)
				(type default)
			)
			(layer "F.Fab")
		)
		(fp_line
			(start 0.67945 -0.3048)
			(end 0.67945 0.3048)
			(stroke
				(width 0.1)
				(type default)
			)
			(layer "F.Fab")
		)
		(fp_line
			(start 0.67945 0.3048)
			(end 0.120396 0.3048)
			(stroke
				(width 0.1)
				(type default)
			)
			(layer "F.Fab")
		)
		(pad "1" smd circle
			(at -0.40005 0)
			(size 0 0)
			(layers "F.Cu" "F.Mask" "F.Paste")
			(net "P3V3_AUX")
		)
		(pad "2" smd circle
			(at 0.40005 0)
			(size 0 0)
			(layers "F.Cu" "F.Mask" "F.Paste")
			(net "SSD_8_15_ADC_ALERT_N")
		)
	)
	(footprint ""
		(layer "F.Cu")
		(at 224.722944 -98.36912 -90)
		(property "Reference" "PR205"
			(at 0 0 270)
			(layer "F.SilkS")
			(hide yes)
			(effects
				(font
					(size 1.27 1.27)
				)
			)
		)
		(property "Value" ""
			(at 0 0 270)
			(layer "F.Fab")
			(effects
				(font
					(size 1.27 1.27)
				)
			)
		)
		(duplicate_pad_numbers_are_jumpers no)
		(fp_line
			(start -0.7874 0.4064)
			(end -0.7874 -0.4064)
			(stroke
				(width 0.1524)
				(type default)
			)
			(layer "F.SilkS")
		)
		(fp_line
			(start 0.7874 0.4064)
			(end -0.7874 0.4064)
			(stroke
				(width 0.1524)
				(type default)
			)
			(layer "F.SilkS")
		)
		(fp_line
			(start -0.7874 -0.4064)
			(end 0.7874 -0.4064)
			(stroke
				(width 0.1524)
				(type default)
			)
			(layer "F.SilkS")
		)
		(fp_line
			(start 0.7874 -0.4064)
			(end 0.7874 0.4064)
			(stroke
				(width 0.1524)
				(type default)
			)
			(layer "F.SilkS")
		)
		(fp_line
			(start -0.67945 0.3048)
			(end -0.67945 -0.305054)
			(stroke
				(width 0.1)
				(type default)
			)
			(layer "F.Fab")
		)
		(fp_line
			(start -0.12065 0.3048)
			(end -0.67945 0.3048)
			(stroke
				(width 0.1)
				(type default)
			)
			(layer "F.Fab")
		)
		(fp_line
			(start 0.120396 0.3048)
			(end 0.120396 0.2794)
			(stroke
				(width 0.1)
				(type default)
			)
			(layer "F.Fab")
		)
		(fp_line
			(start 0.67945 0.3048)
			(end 0.120396 0.3048)
			(stroke
				(width 0.1)
				(type default)
			)
			(layer "F.Fab")
		)
		(fp_line
			(start -0.12065 0.2794)
			(end -0.12065 0.3048)
			(stroke
				(width 0.1)
				(type default)
			)
			(layer "F.Fab")
		)
		(fp_line
			(start 0.120396 0.2794)
			(end -0.12065 0.2794)
			(stroke
				(width 0.1)
				(type default)
			)
			(layer "F.Fab")
		)
		(fp_line
			(start -0.12065 -0.2794)
			(end 0.12065 -0.2794)
			(stroke
				(width 0.1)
				(type default)
			)
			(layer "F.Fab")
		)
		(fp_line
			(start 0.12065 -0.2794)
			(end 0.12065 -0.3048)
			(stroke
				(width 0.1)
				(type default)
			)
			(layer "F.Fab")
		)
		(fp_line
			(start 0.12065 -0.3048)
			(end 0.67945 -0.3048)
			(stroke
				(width 0.1)
				(type default)
			)
			(layer "F.Fab")
		)
		(fp_line
			(start 0.67945 -0.3048)
			(end 0.67945 0.3048)
			(stroke
				(width 0.1)
				(type default)
			)
			(layer "F.Fab")
		)
		(fp_line
			(start -0.67945 -0.305054)
			(end -0.12065 -0.305054)
			(stroke
				(width 0.1)
				(type default)
			)
			(layer "F.Fab")
		)
		(fp_line
			(start -0.12065 -0.305054)
			(end -0.12065 -0.2794)
			(stroke
				(width 0.1)
				(type default)
			)
			(layer "F.Fab")
		)
		(pad "1" smd circle
			(at -0.40005 0 270)
			(size 0 0)
			(layers "F.Cu" "F.Mask" "F.Paste")
			(net "P12V_NIC3_OCP")
		)
		(pad "2" smd circle
			(at 0.40005 0 270)
			(size 0 0)
			(layers "F.Cu" "F.Mask" "F.Paste")
			(net "GND")
		)
	)
	(footprint ""
		(layer "F.Cu")
		(at 146.253454 -294.591232)
		(property "Reference" "L106"
			(at 0 0 0)
			(layer "F.SilkS")
			(hide yes)
			(effects
				(font
					(size 1.27 1.27)
				)
			)
		)
		(property "Value" ""
			(at 0 0 0)
			(layer "F.Fab")
			(effects
				(font
					(size 1.27 1.27)
				)
			)
		)
		(duplicate_pad_numbers_are_jumpers no)
		(fp_line
			(start -1.63576 -0.8128)
			(end -1.63576 0.8128)
			(stroke
				(width 0.1524)
				(type default)
			)
			(layer "F.SilkS")
		)
		(fp_line
			(start -1.63576 -0.8128)
			(end 1.63576 -0.8128)
			(stroke
				(width 0.1524)
				(type default)
			)
			(layer "F.SilkS")
		)
		(fp_line
			(start 1.63576 -0.8128)
			(end 1.63576 0.8128)
			(stroke
				(width 0.1524)
				(type default)
			)
			(layer "F.SilkS")
		)
		(fp_line
			(start 1.63576 0.8128)
			(end -1.63576 0.8128)
			(stroke
				(width 0.1524)
				(type default)
			)
			(layer "F.SilkS")
		)
		(fp_line
			(start -1.56083 -0.738632)
			(end -1.56083 0.7366)
			(stroke
				(width 0.1)
				(type default)
			)
			(layer "F.Fab")
		)
		(fp_line
			(start -1.56083 0.7366)
			(end -1.524 0.7366)
			(stroke
				(width 0.1)
				(type default)
			)
			(layer "F.Fab")
		)
		(fp_line
			(start -1.524 0.7366)
			(end 1.524 0.7366)
			(stroke
				(width 0.1)
				(type default)
			)
			(layer "F.Fab")
		)
		(fp_line
			(start 1.524 0.7366)
			(end 1.560576 0.7366)
			(stroke
				(width 0.1)
				(type default)
			)
			(layer "F.Fab")
		)
		(fp_line
			(start 1.560576 -0.738632)
			(end -1.56083 -0.738632)
			(stroke
				(width 0.1)
				(type default)
			)
			(layer "F.Fab")
		)
		(fp_line
			(start 1.560576 0.7366)
			(end 1.560576 -0.738632)
			(stroke
				(width 0.1)
				(type default)
			)
			(layer "F.Fab")
		)
		(pad "1" smd rect
			(at -0.94996 0 180)
			(size 1.1176 1.3716)
			(layers "F.Cu" "F.Mask" "F.Paste")
			(net "P1V8_PLL0_PEX1")
		)
		(pad "2" smd rect
			(at 0.94996 0 180)
			(size 1.1176 1.3716)
			(layers "F.Cu" "F.Mask" "F.Paste")
			(net "PCEPLL2_VDDA18_PEX1")
		)
	)
	(footprint ""
		(layer "F.Cu")
		(at 92.997782 -296.365168 90)
		(property "Reference" "C2781"
			(at 0 0 90)
			(layer "F.SilkS")
			(hide yes)
			(effects
				(font
					(size 1.27 1.27)
				)
			)
		)
		(property "Value" ""
			(at 0 0 90)
			(layer "F.Fab")
			(effects
				(font
					(size 1.27 1.27)
				)
			)
		)
		(duplicate_pad_numbers_are_jumpers no)
		(fp_line
			(start 0.7874 -0.4064)
			(end 0.7874 0.4064)
			(stroke
				(width 0.1524)
				(type default)
			)
			(layer "F.SilkS")
		)
		(fp_line
			(start -0.7874 -0.4064)
			(end 0.7874 -0.4064)
			(stroke
				(width 0.1524)
				(type default)
			)
			(layer "F.SilkS")
		)
		(fp_line
			(start 0.7874 0.4064)
			(end -0.7874 0.4064)
			(stroke
				(width 0.1524)
				(type default)
			)
			(layer "F.SilkS")
		)
		(fp_line
			(start -0.7874 0.4064)
			(end -0.7874 -0.4064)
			(stroke
				(width 0.1524)
				(type default)
			)
			(layer "F.SilkS")
		)
		(fp_line
			(start -0.12065 -0.305054)
			(end -0.12065 -0.2794)
			(stroke
				(width 0.1)
				(type default)
			)
			(layer "F.Fab")
		)
		(fp_line
			(start -0.67945 -0.305054)
			(end -0.12065 -0.305054)
			(stroke
				(width 0.1)
				(type default)
			)
			(layer "F.Fab")
		)
		(fp_line
			(start 0.67945 -0.3048)
			(end 0.67945 0.3048)
			(stroke
				(width 0.1)
				(type default)
			)
			(layer "F.Fab")
		)
		(fp_line
			(start 0.12065 -0.3048)
			(end 0.67945 -0.3048)
			(stroke
				(width 0.1)
				(type default)
			)
			(layer "F.Fab")
		)
		(fp_line
			(start 0.12065 -0.2794)
			(end 0.12065 -0.3048)
			(stroke
				(width 0.1)
				(type default)
			)
			(layer "F.Fab")
		)
		(fp_line
			(start -0.12065 -0.2794)
			(end 0.12065 -0.2794)
			(stroke
				(width 0.1)
				(type default)
			)
			(layer "F.Fab")
		)
		(fp_line
			(start 0.120396 0.2794)
			(end -0.12065 0.2794)
			(stroke
				(width 0.1)
				(type default)
			)
			(layer "F.Fab")
		)
		(fp_line
			(start -0.12065 0.2794)
			(end -0.12065 0.3048)
			(stroke
				(width 0.1)
				(type default)
			)
			(layer "F.Fab")
		)
		(fp_line
			(start 0.67945 0.3048)
			(end 0.120396 0.3048)
			(stroke
				(width 0.1)
				(type default)
			)
			(layer "F.Fab")
		)
		(fp_line
			(start 0.120396 0.3048)
			(end 0.120396 0.2794)
			(stroke
				(width 0.1)
				(type default)
			)
			(layer "F.Fab")
		)
		(fp_line
			(start -0.12065 0.3048)
			(end -0.67945 0.3048)
			(stroke
				(width 0.1)
				(type default)
			)
			(layer "F.Fab")
		)
		(fp_line
			(start -0.67945 0.3048)
			(end -0.67945 -0.305054)
			(stroke
				(width 0.1)
				(type default)
			)
			(layer "F.Fab")
		)
		(pad "1" smd circle
			(at -0.40005 0 90)
			(size 0 0)
			(layers "F.Cu" "F.Mask" "F.Paste")
			(net "GND")
		)
		(pad "2" smd circle
			(at 0.40005 0 90)
			(size 0 0)
			(layers "F.Cu" "F.Mask" "F.Paste")
			(net "P1V8_PEX")
		)
	)
	(footprint ""
		(layer "F.Cu")
		(at 336.443574 -43.85691)
		(property "Reference" "R630"
			(at 0 0 0)
			(layer "F.SilkS")
			(hide yes)
			(effects
				(font
					(size 1.27 1.27)
				)
			)
		)
		(property "Value" ""
			(at 0 0 0)
			(layer "F.Fab")
			(effects
				(font
					(size 1.27 1.27)
				)
			)
		)
		(duplicate_pad_numbers_are_jumpers no)
		(fp_line
			(start -0.7874 -0.4064)
			(end 0.7874 -0.4064)
			(stroke
				(width 0.1524)
				(type default)
			)
			(layer "F.SilkS")
		)
		(fp_line
			(start -0.7874 0.4064)
			(end -0.7874 -0.4064)
			(stroke
				(width 0.1524)
				(type default)
			)
			(layer "F.SilkS")
		)
		(fp_line
			(start 0.7874 -0.4064)
			(end 0.7874 0.4064)
			(stroke
				(width 0.1524)
				(type default)
			)
			(layer "F.SilkS")
		)
		(fp_line
			(start 0.7874 0.4064)
			(end -0.7874 0.4064)
			(stroke
				(width 0.1524)
				(type default)
			)
			(layer "F.SilkS")
		)
		(fp_line
			(start -0.67945 -0.305054)
			(end -0.12065 -0.305054)
			(stroke
				(width 0.1)
				(type default)
			)
			(layer "F.Fab")
		)
		(fp_line
			(start -0.67945 0.3048)
			(end -0.67945 -0.305054)
			(stroke
				(width 0.1)
				(type default)
			)
			(layer "F.Fab")
		)
		(fp_line
			(start -0.12065 -0.305054)
			(end -0.12065 -0.2794)
			(stroke
				(width 0.1)
				(type default)
			)
			(layer "F.Fab")
		)
		(fp_line
			(start -0.12065 -0.2794)
			(end 0.12065 -0.2794)
			(stroke
				(width 0.1)
				(type default)
			)
			(layer "F.Fab")
		)
		(fp_line
			(start -0.12065 0.2794)
			(end -0.12065 0.3048)
			(stroke
				(width 0.1)
				(type default)
			)
			(layer "F.Fab")
		)
		(fp_line
			(start -0.12065 0.3048)
			(end -0.67945 0.3048)
			(stroke
				(width 0.1)
				(type default)
			)
			(layer "F.Fab")
		)
		(fp_line
			(start 0.120396 0.2794)
			(end -0.12065 0.2794)
			(stroke
				(width 0.1)
				(type default)
			)
			(layer "F.Fab")
		)
		(fp_line
			(start 0.120396 0.3048)
			(end 0.120396 0.2794)
			(stroke
				(width 0.1)
				(type default)
			)
			(layer "F.Fab")
		)
		(fp_line
			(start 0.12065 -0.3048)
			(end 0.67945 -0.3048)
			(stroke
				(width 0.1)
				(type default)
			)
			(layer "F.Fab")
		)
		(fp_line
			(start 0.12065 -0.2794)
			(end 0.12065 -0.3048)
			(stroke
				(width 0.1)
				(type default)
			)
			(layer "F.Fab")
		)
		(fp_line
			(start 0.67945 -0.3048)
			(end 0.67945 0.3048)
			(stroke
				(width 0.1)
				(type default)
			)
			(layer "F.Fab")
		)
		(fp_line
			(start 0.67945 0.3048)
			(end 0.120396 0.3048)
			(stroke
				(width 0.1)
				(type default)
			)
			(layer "F.Fab")
		)
		(pad "1" smd circle
			(at -0.40005 0)
			(size 0 0)
			(layers "F.Cu" "F.Mask" "F.Paste")
			(net "SSD11_ADC_A1")
		)
		(pad "2" smd circle
			(at 0.40005 0)
			(size 0 0)
			(layers "F.Cu" "F.Mask" "F.Paste")
			(net "GND")
		)
	)
)
